# BASEBOARD_FAB2 (Tioga Pass) — schematic netlist excerpt (pin names and nets, part order shuffled) for the footprints in the layout excerpt that follows; sources: Cadence DE-HDL packaged netlist, KiCad conversion of Wiwynn_Tioga_Pass_MB.brd

J9U1  SCONN288_H44441003  SCONN  pkg PIP  page 80
  \12v\(1)  = P12V_NVDIMM_GHJ
  VSS(93)  = GND
  DQ(4)  = M_H_DQ<4>
  VSS(92)  = GND
  DQ(0)  = M_H_DQ<0>
  VSS(91)  = GND
  DQS9P  = M_H_DQS_DP<9>
  DQS9N  = M_H_DQS_DN<9>
  VSS(90)  = GND
  DQ(6)  = M_H_DQ<6>
  VSS(89)  = GND
  DQ(2)  = M_H_DQ<2>
  VSS(88)  = GND
  DQ(12)  = M_H_DQ<12>
  VSS(87)  = GND
  DQ(8)  = M_H_DQ<8>
  VSS(86)  = GND
  DQS10P  = M_H_DQS_DP<10>
  DQS10N  = M_H_DQS_DN<10>
  VSS(85)  = GND
  DQ(14)  = M_H_DQ<14>
  VSS(84)  = GND
  DQ(10)  = M_H_DQ<10>
  VSS(83)  = GND
  DQ(20)  = M_H_DQ<20>
  VSS(82)  = GND
  DQ(16)  = M_H_DQ<16>
  VSS(81)  = GND
  DQS11P  = M_H_DQS_DP<11>
  DQS11N  = M_H_DQS_DN<11>
  VSS(80)  = GND
  DQ(22)  = M_H_DQ<22>
  VSS(79)  = GND
  DQ(18)  = M_H_DQ<18>
  VSS(78)  = GND
  DQ(28)  = M_H_DQ<28>
  VSS(77)  = GND
  DQ(24)  = M_H_DQ<24>
  VSS(76)  = GND
  DQS12P  = M_H_DQS_DP<12>
  DQS12N  = M_H_DQS_DN<12>
  VSS(75)  = GND
  DQ(30)  = M_H_DQ<30>
  VSS(74)  = GND
  DQ(26)  = M_H_DQ<26>
  VSS(73)  = GND
  CB(4)  = M_H_ECC<4>
  VSS(72)  = GND
  CB(0)  = M_H_ECC<0>
  VSS(71)  = GND
  DQS17P  = M_H_DQS_DP<17>
  DQS17N  = M_H_DQS_DN<17>
  VSS(70)  = GND
  CB(6)  = M_H_ECC<6>
  VSS(69)  = GND
  CB(2)  = M_H_ECC<2>
  VSS(68)  = GND
  RESET_N  = M_GHJ_RST_N
  VDD(25)  = PVDDQ_GHJ
  CKE(0)  = M_H_CKE<2>
  VDD(24)  = PVDDQ_GHJ
  ACT_N  = M_H_ACT_N
  BG(0)  = M_H_BG<0>
  VDD(23)  = PVDDQ_GHJ
  A12  = M_H_MA<12>
  A9  = M_H_MA<9>
  VDD(22)  = PVDDQ_GHJ
  A8  = M_H_MA<8>
  A6  = M_H_MA<6>
  VDD(21)  = PVDDQ_GHJ
  A3  = M_H_MA<3>
  A1  = M_H_MA<1>
  VDD(20)  = PVDDQ_GHJ
  CK0P  = M_H_CLK_DP<2>
  CK0N  = M_H_CLK_DN<2>
  VDD(19)  = PVDDQ_GHJ
  VTT(1)  = PVTT_GHJ
  EVENT_N  = FM_DIMM_EVENT_COD_N
  A0  = M_H_MA<0>
  VDD(18)  = PVDDQ_GHJ
  BA(0)  = M_H_BA<0>
  A16_RAS_N  = M_H_MA<16>
  VDD(17)  = PVDDQ_GHJ
  S0_N  = M_H_CS_N<4>
  VDD(16)  = PVDDQ_GHJ
  A15_CAS_N  = M_H_MA<15>
  ODT(0)  = M_H_ODT<2>
  VDD(15)  = PVDDQ_GHJ
  S1_N  = M_H_CS_N<5>
  VDD(14)  = PVDDQ_GHJ
  ODT(1)  = M_H_ODT<3>
  VDD(13)  = PVDDQ_GHJ
  S2_N_C(0)  = M_H_CS_N<6>
  VSS(67)  = GND
  DQ(36)  = M_H_DQ<36>
  VSS(66)  = GND
  DQ(32)  = M_H_DQ<32>
  VSS(65)  = GND
  DQS13P  = M_H_DQS_DP<13>
  DQS13N  = M_H_DQS_DN<13>
  VSS(64)  = GND
  DQ(38)  = M_H_DQ<38>
  VSS(63)  = GND
  DQ(34)  = M_H_DQ<34>
  VSS(62)  = GND
  DQ(44)  = M_H_DQ<44>
  VSS(61)  = GND
  DQ(40)  = M_H_DQ<40>
  VSS(60)  = GND
  DQS14P  = M_H_DQS_DP<14>
  DQS14N  = M_H_DQS_DN<14>
  VSS(59)  = GND
  DQ(46)  = M_H_DQ<46>
  VSS(58)  = GND
  DQ(42)  = M_H_DQ<42>
  VSS(57)  = GND
  DQ(52)  = M_H_DQ<52>
  VSS(56)  = GND
  DQ(48)  = M_H_DQ<48>
  VSS(55)  = GND
  DQS15P  = M_H_DQS_DP<15>
  DQS15N  = M_H_DQS_DN<15>
  VSS(54)  = GND
  DQ(54)  = M_H_DQ<54>
  VSS(53)  = GND
  DQ(50)  = M_H_DQ<50>
  VSS(52)  = GND
  DQ(60)  = M_H_DQ<60>
  VSS(51)  = GND
  DQ(56)  = M_H_DQ<56>
  VSS(50)  = GND
  DQS16P  = M_H_DQS_DP<16>
  DQS16N  = M_H_DQS_DN<16>
  VSS(49)  = GND
  DQ(62)  = M_H_DQ<62>
  VSS(48)  = GND
  DQ(58)  = M_H_DQ<58>
  VSS(47)  = GND
  SA(0)  = PVPP_GHJ
  SA(1)  = PVPP_GHJ
  SCL  = SMB_DDR_GHJ_VPP_SCL
  VPP(4)  = PVPP_GHJ
  VPP(3)  = PVPP_GHJ
  RFU(2)  = TP_CH_H_DIMM0_RFU_2
  \12v\(0)  = P12V_NVDIMM_GHJ
  VREFCA  = M_H_VREF
  VSS(46)  = GND
  DQ(5)  = M_H_DQ<5>
  VSS(45)  = GND
  DQ(1)  = M_H_DQ<1>
  VSS(44)  = GND
  DQS0N  = M_H_DQS_DN<0>
  DQS0P  = M_H_DQS_DP<0>
  VSS(43)  = GND
  DQ(7)  = M_H_DQ<7>
  VSS(42)  = GND
  DQ(3)  = M_H_DQ<3>
  VSS(41)  = GND
  DQ(13)  = M_H_DQ<13>
  VSS(40)  = GND
  DQ(9)  = M_H_DQ<9>
  VSS(39)  = GND
  DQS1N  = M_H_DQS_DN<1>
  DQS1P  = M_H_DQS_DP<1>
  VSS(38)  = GND
  DQ(15)  = M_H_DQ<15>
  VSS(37)  = GND
  DQ(11)  = M_H_DQ<11>
  VSS(36)  = GND
  DQ(21)  = M_H_DQ<21>
  VSS(35)  = GND
  DQ(17)  = M_H_DQ<17>
  VSS(34)  = GND
  DQS2N  = M_H_DQS_DN<2>
  DQS2P  = M_H_DQS_DP<2>
  VSS(33)  = GND
  DQ(23)  = M_H_DQ<23>
  VSS(32)  = GND
  DQ(19)  = M_H_DQ<19>
  VSS(31)  = GND
  DQ(29)  = M_H_DQ<29>
  VSS(30)  = GND
  DQ(25)  = M_H_DQ<25>
  VSS(29)  = GND
  DQS3N  = M_H_DQS_DN<3>
  DQS3P  = M_H_DQS_DP<3>
  VSS(28)  = GND
  DQ(31)  = M_H_DQ<31>
  VSS(27)  = GND
  DQ(27)  = M_H_DQ<27>
  VSS(26)  = GND
  CB(5)  = M_H_ECC<5>
  VSS(25)  = GND
  CB(1)  = M_H_ECC<1>
  VSS(24)  = GND
  DQS8N  = M_H_DQS_DN<8>
  DQS8P  = M_H_DQS_DP<8>
  VSS(23)  = GND
  CB(7)  = M_H_ECC<7>
  VSS(22)  = GND
  CB(3)  = M_H_ECC<3>
  VSS(21)  = GND
  CKE(1)  = M_H_CKE<3>
  VDD(12)  = PVDDQ_GHJ
  RFU(0)  = TP_CH_H_DIMM0_RFU_0
  VDD(11)  = PVDDQ_GHJ
  BG(1)  = M_H_BG<1>
  ALERT_N  = M_H_ALERT_N
  VDD(10)  = PVDDQ_GHJ
  A11  = M_H_MA<11>
  A7  = M_H_MA<7>
  VDD(9)  = PVDDQ_GHJ
  A5  = M_H_MA<5>
  A4  = M_H_MA<4>
  VDD(8)  = PVDDQ_GHJ
  A2  = M_H_MA<2>
  VDD(7)  = PVDDQ_GHJ
  CK1P  = M_H_CLK_DP<3>
  CK1N  = M_H_CLK_DN<3>
  VDD(6)  = PVDDQ_GHJ
  VTT(0)  = PVTT_GHJ
  PAR  = M_H_PAR
  VDD(5)  = PVDDQ_GHJ
  BA(1)  = M_H_BA<1>
  A10  = M_H_MA<10>
  VDD(4)  = PVDDQ_GHJ
  RFU(1)  = TP_CH_H_DIMM0_RFU_1
  A14_WE_N  = M_H_MA<14>
  VDD(3)  = PVDDQ_GHJ
  SAVE_N_NC  = FM_ADR_COMPLETE_GHJ_N
  VDD(2)  = PVDDQ_GHJ
  A13  = M_H_MA<13>
  VDD(1)  = PVDDQ_GHJ
  A17  = M_H_MA<17>
  C(2)  = M_H_C<2>
  VDD(0)  = PVDDQ_GHJ
  S3_N_C(1)  = M_H_CS_N<7>
  SA(2)  = GND
  VSS(20)  = GND
  DQ(37)  = M_H_DQ<37>
  VSS(19)  = GND
  DQ(33)  = M_H_DQ<33>
  VSS(18)  = GND
  DQS4N  = M_H_DQS_DN<4>
  DQS4P  = M_H_DQS_DP<4>
  VSS(17)  = GND
  DQ(39)  = M_H_DQ<39>
  VSS(16)  = GND
  DQ(35)  = M_H_DQ<35>
  VSS(15)  = GND
  DQ(45)  = M_H_DQ<45>
  VSS(14)  = GND
  DQ(41)  = M_H_DQ<41>
  VSS(13)  = GND
  DQS5N  = M_H_DQS_DN<5>
  DQS5P  = M_H_DQS_DP<5>
  VSS(12)  = GND
  DQ(47)  = M_H_DQ<47>
  VSS(11)  = GND
  DQ(43)  = M_H_DQ<43>
  VSS(10)  = GND
  DQ(53)  = M_H_DQ<53>
  VSS(9)  = GND
  DQ(49)  = M_H_DQ<49>
  VSS(8)  = GND
  DQS6N  = M_H_DQS_DN<6>
  DQS6P  = M_H_DQS_DP<6>
  VSS(7)  = GND
  DQ(55)  = M_H_DQ<55>
  VSS(6)  = GND
  DQ(51)  = M_H_DQ<51>
  VSS(5)  = GND
  DQ(61)  = M_H_DQ<61>
  VSS(4)  = GND
  DQ(57)  = M_H_DQ<57>
  VSS(3)  = GND
  DQS7N  = M_H_DQS_DN<7>
  DQS7P  = M_H_DQS_DP<7>
  VSS(2)  = GND
  DQ(63)  = M_H_DQ<63>
  VSS(1)  = GND
  DQ(59)  = M_H_DQ<59>
  VSS(0)  = GND
  VDDSPD  = PVPP_GHJ
  SDA  = SMB_DDR_GHJ_VPP_SDA
  VPP(1)  = PVPP_GHJ
  VPP(0)  = PVPP_GHJ
  VPP(2)  = PVPP_GHJ

(kicad_pcb
	(version 20260206)
	(generator "pcbnew")
	(generator_version "10.0")
	(general
		(thickness 1.6)
		(legacy_teardrops no)
	)
	(paper "A4")
	(title_block
		(title "Wiwynn_Tioga_Pass_MB.brd")
		(comment 1 "Tioga Pass / footprint 3114 of 4770 (J9U1), pads 1-50 of 291")
	)
	(layers
		(0 "F.Cu" signal "TOP")
		(4 "In1.Cu" signal "L2GND")
		(6 "In2.Cu" signal "L3")
		(8 "In3.Cu" signal "L4GND")
		(10 "In4.Cu" signal "L5")
		(12 "In5.Cu" signal "L6GND")
		(14 "In6.Cu" signal "L7VCC")
		(16 "In7.Cu" signal "L8VCC")
		(18 "In8.Cu" signal "L9GND")
		(20 "In9.Cu" signal "L10")
		(22 "In10.Cu" signal "L11GND")
		(24 "In11.Cu" signal "L12")
		(26 "In12.Cu" signal "L13GND")
		(2 "B.Cu" signal "BOTTOM")
		(9 "F.Adhes" user "F.Adhesive")
		(11 "B.Adhes" user "B.Adhesive")
		(13 "F.Paste" user "Package Geometry/Pastemask Top")
		(15 "B.Paste" user "Package Geometry/Pastemask Bottom")
		(5 "F.SilkS" user "Ref Des/Silkscreen Top")
		(7 "B.SilkS" user "Ref Des/Silkscreen Bottom")
		(1 "F.Mask" user "Board Geometry/Soldermask Top")
		(3 "B.Mask" user "Board Geometry/Soldermask Bottom")
		(17 "Dwgs.User" user "User.Drawings")
		(19 "Cmts.User" user "User.Comments")
		(21 "Eco1.User" user "User.Eco1")
		(23 "Eco2.User" user "User.Eco2")
		(25 "Edge.Cuts" user "Board Geometry/Outline")
		(27 "Margin" user)
		(31 "F.CrtYd" user "Package Geometry/Place Bound Top")
		(29 "B.CrtYd" user "Package Geometry/Place Bound Bottom")
		(35 "F.Fab" user "Ref Des/Assembly Top")
		(33 "B.Fab" user "Ref Des/Assembly Bottom")
	)
	(footprint ""
		(layer "B.Cu")
		(at 29.699458 -15.222982 90)
		(property "Reference" "J9U1"
			(at 2.276348 37.991542 0)
			(unlocked yes)
			(layer "B.SilkS")
			(effects
				(font
					(size 0.7874 0.5842)
					(thickness 0.1524)
				)
				(justify left mirror)
			)
		)
		(property "Value" ""
			(at 0 0 90)
			(layer "B.Fab")
			(effects
				(font
					(size 1.27 1.27)
				)
				(justify mirror)
			)
		)
		(duplicate_pad_numbers_are_jumpers no)
		(pad "" thru_hole circle
			(at -2.29997 -5.649976 270)
			(size 2.8194 2.8194)
			(drill 2.4384)
			(layers "*.Cu" "*.Mask")
			(remove_unused_layers no)
			(clearance 0.127)
			(thermal_gap 0.127)
		)
		(pad "" thru_hole oval
			(at -2.29997 68.90004 270)
			(size 2.8194 1.5748)
			(drill oval 2.4384 1.1938)
			(layers "*.Cu" "*.Mask")
			(remove_unused_layers no)
			(clearance 0.127)
			(thermal_gap 0.127)
		)
		(pad "" thru_hole circle
			(at -2.29997 132.299964 270)
			(size 2.8194 2.8194)
			(drill 2.4384)
			(layers "*.Cu" "*.Mask")
			(remove_unused_layers no)
			(clearance 0.127)
			(thermal_gap 0.127)
		)
		(pad "1" smd rect
			(at 0 0 270)
			(size 1.8034 0.508)
			(layers "B.Cu" "B.Mask" "B.Paste")
			(net "P12V_NVDIMM_GHJ")
		)
		(pad "2" smd rect
			(at 0 0.849884 270)
			(size 1.8034 0.508)
			(layers "B.Cu" "B.Mask" "B.Paste")
			(net "GND")
		)
		(pad "3" smd rect
			(at 0 1.700022 270)
			(size 1.8034 0.508)
			(layers "B.Cu" "B.Mask" "B.Paste")
			(net "M_H_DQ<4>")
		)
		(pad "4" smd rect
			(at 0 2.549906 270)
			(size 1.8034 0.508)
			(layers "B.Cu" "B.Mask" "B.Paste")
			(net "GND")
		)
		(pad "5" smd rect
			(at 0 3.400044 270)
			(size 1.8034 0.508)
			(layers "B.Cu" "B.Mask" "B.Paste")
			(net "M_H_DQ<0>")
		)
		(pad "6" smd rect
			(at 0 4.249928 270)
			(size 1.8034 0.508)
			(layers "B.Cu" "B.Mask" "B.Paste")
			(net "GND")
		)
		(pad "7" smd rect
			(at 0 5.100066 270)
			(size 1.8034 0.508)
			(layers "B.Cu" "B.Mask" "B.Paste")
			(net "M_H_DQS_DP<9>")
		)
		(pad "8" smd rect
			(at 0 5.94995 270)
			(size 1.8034 0.508)
			(layers "B.Cu" "B.Mask" "B.Paste")
			(net "M_H_DQS_DN<9>")
		)
		(pad "9" smd rect
			(at 0 6.800088 270)
			(size 1.8034 0.508)
			(layers "B.Cu" "B.Mask" "B.Paste")
			(net "GND")
		)
		(pad "10" smd rect
			(at 0 7.649972 270)
			(size 1.8034 0.508)
			(layers "B.Cu" "B.Mask" "B.Paste")
			(net "M_H_DQ<6>")
		)
		(pad "11" smd rect
			(at 0 8.50011 270)
			(size 1.8034 0.508)
			(layers "B.Cu" "B.Mask" "B.Paste")
			(net "GND")
		)
		(pad "12" smd rect
			(at 0 9.349994 270)
			(size 1.8034 0.508)
			(layers "B.Cu" "B.Mask" "B.Paste")
			(net "M_H_DQ<2>")
		)
		(pad "13" smd rect
			(at 0 10.199878 270)
			(size 1.8034 0.508)
			(layers "B.Cu" "B.Mask" "B.Paste")
			(net "GND")
		)
		(pad "14" smd rect
			(at 0 11.050016 270)
			(size 1.8034 0.508)
			(layers "B.Cu" "B.Mask" "B.Paste")
			(net "M_H_DQ<12>")
		)
		(pad "15" smd rect
			(at 0 11.8999 270)
			(size 1.8034 0.508)
			(layers "B.Cu" "B.Mask" "B.Paste")
			(net "GND")
		)
		(pad "16" smd rect
			(at 0 12.750038 270)
			(size 1.8034 0.508)
			(layers "B.Cu" "B.Mask" "B.Paste")
			(net "M_H_DQ<8>")
		)
		(pad "17" smd rect
			(at 0 13.599922 270)
			(size 1.8034 0.508)
			(layers "B.Cu" "B.Mask" "B.Paste")
			(net "GND")
		)
		(pad "18" smd rect
			(at 0 14.45006 270)
			(size 1.8034 0.508)
			(layers "B.Cu" "B.Mask" "B.Paste")
			(net "M_H_DQS_DP<10>")
		)
		(pad "19" smd rect
			(at 0 15.299944 270)
			(size 1.8034 0.508)
			(layers "B.Cu" "B.Mask" "B.Paste")
			(net "M_H_DQS_DN<10>")
		)
		(pad "20" smd rect
			(at 0 16.150082 270)
			(size 1.8034 0.508)
			(layers "B.Cu" "B.Mask" "B.Paste")
			(net "GND")
		)
		(pad "21" smd rect
			(at 0 16.999966 270)
			(size 1.8034 0.508)
			(layers "B.Cu" "B.Mask" "B.Paste")
			(net "M_H_DQ<14>")
		)
		(pad "22" smd rect
			(at 0 17.850104 270)
			(size 1.8034 0.508)
			(layers "B.Cu" "B.Mask" "B.Paste")
			(net "GND")
		)
		(pad "23" smd rect
			(at 0 18.699988 270)
			(size 1.8034 0.508)
			(layers "B.Cu" "B.Mask" "B.Paste")
			(net "M_H_DQ<10>")
		)
		(pad "24" smd rect
			(at 0 19.550126 270)
			(size 1.8034 0.508)
			(layers "B.Cu" "B.Mask" "B.Paste")
			(net "GND")
		)
		(pad "25" smd rect
			(at 0 20.40001 270)
			(size 1.8034 0.508)
			(layers "B.Cu" "B.Mask" "B.Paste")
			(net "M_H_DQ<20>")
		)
		(pad "26" smd rect
			(at 0 21.249894 270)
			(size 1.8034 0.508)
			(layers "B.Cu" "B.Mask" "B.Paste")
			(net "GND")
		)
		(pad "27" smd rect
			(at 0 22.100032 270)
			(size 1.8034 0.508)
			(layers "B.Cu" "B.Mask" "B.Paste")
			(net "M_H_DQ<16>")
		)
		(pad "28" smd rect
			(at 0 22.949916 270)
			(size 1.8034 0.508)
			(layers "B.Cu" "B.Mask" "B.Paste")
			(net "GND")
		)
		(pad "29" smd rect
			(at 0 23.800054 270)
			(size 1.8034 0.508)
			(layers "B.Cu" "B.Mask" "B.Paste")
			(net "M_H_DQS_DP<11>")
		)
		(pad "30" smd rect
			(at 0 24.649938 270)
			(size 1.8034 0.508)
			(layers "B.Cu" "B.Mask" "B.Paste")
			(net "M_H_DQS_DN<11>")
		)
		(pad "31" smd rect
			(at 0 25.500076 270)
			(size 1.8034 0.508)
			(layers "B.Cu" "B.Mask" "B.Paste")
			(net "GND")
		)
		(pad "32" smd rect
			(at 0 26.34996 270)
			(size 1.8034 0.508)
			(layers "B.Cu" "B.Mask" "B.Paste")
			(net "M_H_DQ<22>")
		)
		(pad "33" smd rect
			(at 0 27.200098 270)
			(size 1.8034 0.508)
			(layers "B.Cu" "B.Mask" "B.Paste")
			(net "GND")
		)
		(pad "34" smd rect
			(at 0 28.049982 270)
			(size 1.8034 0.508)
			(layers "B.Cu" "B.Mask" "B.Paste")
			(net "M_H_DQ<18>")
		)
		(pad "35" smd rect
			(at 0 28.90012 270)
			(size 1.8034 0.508)
			(layers "B.Cu" "B.Mask" "B.Paste")
			(net "GND")
		)
		(pad "36" smd rect
			(at 0 29.750004 270)
			(size 1.8034 0.508)
			(layers "B.Cu" "B.Mask" "B.Paste")
			(net "M_H_DQ<28>")
		)
		(pad "37" smd rect
			(at 0 30.599888 270)
			(size 1.8034 0.508)
			(layers "B.Cu" "B.Mask" "B.Paste")
			(net "GND")
		)
		(pad "38" smd rect
			(at 0 31.450026 270)
			(size 1.8034 0.508)
			(layers "B.Cu" "B.Mask" "B.Paste")
			(net "M_H_DQ<24>")
		)
		(pad "39" smd rect
			(at 0 32.29991 270)
			(size 1.8034 0.508)
			(layers "B.Cu" "B.Mask" "B.Paste")
			(net "GND")
		)
		(pad "40" smd rect
			(at 0 33.150048 270)
			(size 1.8034 0.508)
			(layers "B.Cu" "B.Mask" "B.Paste")
			(net "M_H_DQS_DP<12>")
		)
		(pad "41" smd rect
			(at 0 33.999932 270)
			(size 1.8034 0.508)
			(layers "B.Cu" "B.Mask" "B.Paste")
			(net "M_H_DQS_DN<12>")
		)
		(pad "42" smd rect
			(at 0 34.85007 270)
			(size 1.8034 0.508)
			(layers "B.Cu" "B.Mask" "B.Paste")
			(net "GND")
		)
		(pad "43" smd rect
			(at 0 35.699954 270)
			(size 1.8034 0.508)
			(layers "B.Cu" "B.Mask" "B.Paste")
			(net "M_H_DQ<30>")
		)
		(pad "44" smd rect
			(at 0 36.550092 270)
			(size 1.8034 0.508)
			(layers "B.Cu" "B.Mask" "B.Paste")
			(net "GND")
		)
		(pad "45" smd rect
			(at 0 37.399976 270)
			(size 1.8034 0.508)
			(layers "B.Cu" "B.Mask" "B.Paste")
			(net "M_H_DQ<26>")
		)
		(pad "46" smd rect
			(at 0 38.250114 270)
			(size 1.8034 0.508)
			(layers "B.Cu" "B.Mask" "B.Paste")
			(net "GND")
		)
		(pad "47" smd rect
			(at 0 39.099998 270)
			(size 1.8034 0.508)
			(layers "B.Cu" "B.Mask" "B.Paste")
			(net "M_H_ECC<4>")
		)
	)
)
